G04*
G04 #@! TF.GenerationSoftware,Altium Limited,Altium Designer,23.7.1 (13)*
G04*
G04 Layer_Color=32768*
%FSLAX25Y25*%
%MOIN*%
G70*
G04*
G04 #@! TF.SameCoordinates,AF00DCEB-AC48-4C7C-91EA-99F42E284231*
G04*
G04*
G04 #@! TF.FilePolarity,Positive*
G04*
G01*
G75*
G36*
X266536Y-344094D02*
X246850D01*
Y-324409D01*
X266536D01*
Y-344094D01*
D02*
G37*
G36*
X266142Y-186615D02*
X246456D01*
Y-166929D01*
X266142D01*
Y-186615D01*
D02*
G37*
G36*
X462993Y-344095D02*
X443307D01*
Y-324410D01*
X462993D01*
Y-344095D01*
D02*
G37*
G36*
X462992Y-186615D02*
X443306D01*
Y-166929D01*
X462992D01*
Y-186615D01*
D02*
G37*
M02*
